(kicad_pcb
	(version 20260206)
	(generator "pcbnew")
	(generator_version "10.0")
	(general
		(thickness 1.6)
		(legacy_teardrops no)
	)
	(paper "A4")
	(title_block
		(title "Bryce Canyon_IOM_M2_16342-2_OCP.brd")
		(comment 1 "Bryce Canyon / footprints 207-212 of 1146")
	)
	(layers
		(0 "F.Cu" signal "TOP")
		(4 "In1.Cu" signal "L2GND")
		(6 "In2.Cu" signal "L3")
		(8 "In3.Cu" signal "L4VCC")
		(10 "In4.Cu" signal "L5VCC")
		(12 "In5.Cu" signal "L6")
		(14 "In6.Cu" signal "L7GND")
		(2 "B.Cu" signal "BOTTOM")
		(9 "F.Adhes" user "F.Adhesive")
		(11 "B.Adhes" user "B.Adhesive")
		(13 "F.Paste" user "Package Geometry/Pastemask Top")
		(15 "B.Paste" user "Package Geometry/Pastemask Bottom")
		(5 "F.SilkS" user "Ref Des/Silkscreen Top")
		(7 "B.SilkS" user "Ref Des/Silkscreen Bottom")
		(1 "F.Mask" user "Board Geometry/Soldermask Top")
		(3 "B.Mask" user "Board Geometry/Soldermask Bottom")
		(17 "Dwgs.User" user "User.Drawings")
		(19 "Cmts.User" user "User.Comments")
		(21 "Eco1.User" user "User.Eco1")
		(23 "Eco2.User" user "User.Eco2")
		(25 "Edge.Cuts" user "Board Geometry/Outline")
		(27 "Margin" user)
		(31 "F.CrtYd" user "Package Geometry/Place Bound Top")
		(29 "B.CrtYd" user "Package Geometry/Place Bound Bottom")
		(35 "F.Fab" user "Ref Des/Assembly Top")
		(33 "B.Fab" user "Ref Des/Assembly Bottom")
	)
	(footprint ""
		(layer "F.Cu")
		(at 81.28 -136.017 180)
		(property "Reference" "R39"
			(at 0 0 180)
			(layer "F.SilkS")
			(hide yes)
			(effects
				(font
					(size 1.27 1.27)
				)
			)
		)
		(property "Value" "0R2J-2-GP"
			(at 0.064008 -3.993896 180)
			(unlocked yes)
			(layer "F.Fab")
			(hide yes)
			(effects
				(font
					(size 1.016 1.016)
					(thickness 0.1524)
				)
			)
		)
		(property "Device Type" "R402H16"
			(at 0.064008 -5.517896 180)
			(unlocked yes)
			(layer "F.Fab")
			(hide yes)
			(effects
				(font
					(size 1.016 1.016)
					(thickness 0.1524)
				)
			)
		)
		(duplicate_pad_numbers_are_jumpers no)
		(fp_line
			(start 0.508 -0.9398)
			(end -0.508 -0.9398)
			(stroke
				(width 0.1524)
				(type default)
			)
			(layer "F.SilkS")
		)
		(fp_line
			(start -0.508 -0.9398)
			(end -0.508 0.9398)
			(stroke
				(width 0.1524)
				(type default)
			)
			(layer "F.SilkS")
		)
		(fp_rect
			(start -0.508 0.9398)
			(end 0.508 -0.9398)
			(stroke
				(width 0)
				(type default)
			)
			(fill no)
			(layer "F.CrtYd")
		)
		(fp_rect
			(start -0.508 0.9398)
			(end 0.508 -0.9398)
			(stroke
				(width 0)
				(type default)
			)
			(fill no)
			(layer "F.Fab")
		)
		(pad "1" smd custom
			(at 0 -0.4445 180)
			(size 0.1397 0.1397)
			(layers "F.Cu" "F.Mask" "F.Paste")
			(net "D_FLIP_D")
			(options
				(clearance outline)
				(anchor circle)
			)
			(primitives
				(gr_poly
					(pts
						(arc
							(start -0.1778 -0.2794)
							(mid -0.249642 -0.249642)
							(end -0.2794 -0.1778)
						)
						(arc
							(start -0.2794 0.1778)
							(mid -0.249642 0.249642)
							(end -0.1778 0.2794)
						)
						(arc
							(start 0.1778 0.2794)
							(mid 0.249642 0.249642)
							(end 0.2794 0.1778)
						)
						(arc
							(start 0.2794 -0.1778)
							(mid 0.249642 -0.249642)
							(end 0.1778 -0.2794)
						)
					)
					(width 0)
					(fill yes)
				)
			)
		)
		(pad "2" smd custom
			(at 0 0.4445 180)
			(size 0.1397 0.1397)
			(layers "F.Cu" "F.Mask" "F.Paste")
			(net "D_FLIP_Q#")
			(options
				(clearance outline)
				(anchor circle)
			)
			(primitives
				(gr_poly
					(pts
						(arc
							(start -0.1778 -0.2794)
							(mid -0.249642 -0.249642)
							(end -0.2794 -0.1778)
						)
						(arc
							(start -0.2794 0.1778)
							(mid -0.249642 0.249642)
							(end -0.1778 0.2794)
						)
						(arc
							(start 0.1778 0.2794)
							(mid 0.249642 0.249642)
							(end 0.2794 0.1778)
						)
						(arc
							(start 0.2794 -0.1778)
							(mid 0.249642 -0.249642)
							(end 0.1778 -0.2794)
						)
					)
					(width 0)
					(fill yes)
				)
			)
		)
	)
	(footprint ""
		(layer "F.Cu")
		(at 8.886698 -141.008862 90)
		(property "Reference" "R227"
			(at 0 0 90)
			(layer "F.SilkS")
			(hide yes)
			(effects
				(font
					(size 1.27 1.27)
				)
			)
		)
		(property "Value" "120R2F-GP"
			(at 0.064008 -3.993896 90)
			(unlocked yes)
			(layer "F.Fab")
			(hide yes)
			(effects
				(font
					(size 1.016 1.016)
					(thickness 0.1524)
				)
			)
		)
		(property "Device Type" "R402H16"
			(at 0.064008 -5.517896 90)
			(unlocked yes)
			(layer "F.Fab")
			(hide yes)
			(effects
				(font
					(size 1.016 1.016)
					(thickness 0.1524)
				)
			)
		)
		(duplicate_pad_numbers_are_jumpers no)
		(fp_line
			(start 0.508 -0.9398)
			(end -0.508 -0.9398)
			(stroke
				(width 0.1524)
				(type default)
			)
			(layer "F.SilkS")
		)
		(fp_line
			(start -0.508 -0.9398)
			(end -0.508 0.9398)
			(stroke
				(width 0.1524)
				(type default)
			)
			(layer "F.SilkS")
		)
		(fp_rect
			(start -0.508 0.9398)
			(end 0.508 -0.9398)
			(stroke
				(width 0)
				(type default)
			)
			(fill no)
			(layer "F.CrtYd")
		)
		(fp_rect
			(start -0.508 0.9398)
			(end 0.508 -0.9398)
			(stroke
				(width 0)
				(type default)
			)
			(fill no)
			(layer "F.Fab")
		)
		(pad "1" smd custom
			(at 0 -0.4445 90)
			(size 0.1397 0.1397)
			(layers "F.Cu" "F.Mask" "F.Paste")
			(net "GND")
			(options
				(clearance outline)
				(anchor circle)
			)
			(primitives
				(gr_poly
					(pts
						(arc
							(start -0.1778 -0.2794)
							(mid -0.249642 -0.249642)
							(end -0.2794 -0.1778)
						)
						(arc
							(start -0.2794 0.1778)
							(mid -0.249642 0.249642)
							(end -0.1778 0.2794)
						)
						(arc
							(start 0.1778 0.2794)
							(mid 0.249642 0.249642)
							(end 0.2794 0.1778)
						)
						(arc
							(start 0.2794 -0.1778)
							(mid 0.249642 -0.249642)
							(end 0.1778 -0.2794)
						)
					)
					(width 0)
					(fill yes)
				)
			)
		)
		(pad "2" smd custom
			(at 0 0.4445 90)
			(size 0.1397 0.1397)
			(layers "F.Cu" "F.Mask" "F.Paste")
			(net "MEMWEN")
			(options
				(clearance outline)
				(anchor circle)
			)
			(primitives
				(gr_poly
					(pts
						(arc
							(start -0.1778 -0.2794)
							(mid -0.249642 -0.249642)
							(end -0.2794 -0.1778)
						)
						(arc
							(start -0.2794 0.1778)
							(mid -0.249642 0.249642)
							(end -0.1778 0.2794)
						)
						(arc
							(start 0.1778 0.2794)
							(mid 0.249642 0.249642)
							(end 0.2794 0.1778)
						)
						(arc
							(start 0.2794 -0.1778)
							(mid 0.249642 -0.249642)
							(end 0.1778 -0.2794)
						)
					)
					(width 0)
					(fill yes)
				)
			)
		)
	)
	(footprint ""
		(layer "F.Cu")
		(at 16.691356 -169.1259 -90)
		(property "Reference" "PU10"
			(at 0 0 270)
			(layer "F.SilkS")
			(hide yes)
			(effects
				(font
					(size 1.27 1.27)
				)
			)
		)
		(property "Value" "TPS74801RGW-GP"
			(at -4.7244 -6.223 270)
			(unlocked yes)
			(layer "F.Fab")
			(hide yes)
			(effects
				(font
					(size 1.016 1.016)
					(thickness 0.1524)
				)
			)
		)
		(property "Device Type" "QFN20-1G3D15H40"
			(at -4.7244 -7.747 270)
			(unlocked yes)
			(layer "F.Fab")
			(hide yes)
			(effects
				(font
					(size 1.016 1.016)
					(thickness 0.1524)
				)
			)
		)
		(duplicate_pad_numbers_are_jumpers no)
		(fp_line
			(start -3.5179 3.5179)
			(end -2.2479 3.5179)
			(stroke
				(width 0.1524)
				(type default)
			)
			(layer "F.SilkS")
		)
		(fp_line
			(start 2.2479 3.5179)
			(end 3.5179 3.5179)
			(stroke
				(width 0.1524)
				(type default)
			)
			(layer "F.SilkS")
		)
		(fp_line
			(start 3.5179 3.5179)
			(end 3.5179 2.2479)
			(stroke
				(width 0.1524)
				(type default)
			)
			(layer "F.SilkS")
		)
		(fp_line
			(start 1.299972 3.160522)
			(end 1.299972 3.668522)
			(stroke
				(width 0.1524)
				(type default)
			)
			(layer "F.SilkS")
		)
		(fp_line
			(start -3.5179 2.2479)
			(end -3.5179 3.5179)
			(stroke
				(width 0.1524)
				(type default)
			)
			(layer "F.SilkS")
		)
		(fp_line
			(start -3.160522 1.299972)
			(end -3.922522 1.299972)
			(stroke
				(width 0.1524)
				(type default)
			)
			(layer "F.SilkS")
		)
		(fp_line
			(start 3.160522 -1.299972)
			(end 3.922522 -1.299972)
			(stroke
				(width 0.1524)
				(type default)
			)
			(layer "F.SilkS")
		)
		(fp_line
			(start -1.299972 -3.160522)
			(end -1.299972 -3.668522)
			(stroke
				(width 0.1524)
				(type default)
			)
			(layer "F.SilkS")
		)
		(fp_line
			(start -3.5179 -3.5179)
			(end -3.5179 -2.2479)
			(stroke
				(width 0.1524)
				(type default)
			)
			(layer "F.SilkS")
		)
		(fp_line
			(start -2.2479 -3.5179)
			(end -3.5179 -3.5179)
			(stroke
				(width 0.1524)
				(type default)
			)
			(layer "F.SilkS")
		)
		(fp_poly
			(pts
				(xy 3.5179 -3.5179) (xy 2.2479 -3.5179) (xy 3.5179 -2.2479)
			)
			(stroke
				(width 0)
				(type default)
			)
			(fill yes)
			(layer "F.SilkS")
		)
		(fp_rect
			(start -2.5019 2.5019)
			(end 2.5019 -2.5019)
			(stroke
				(width 0)
				(type default)
			)
			(fill no)
			(layer "F.CrtYd")
		)
		(fp_poly
			(pts
				(xy -3.5179 3.5179) (xy -3.5179 -3.5179) (xy 3.5179 -3.5179) (xy 3.5179 -2.5019) (xy -2.5019 -2.5019)
				(xy -2.5019 2.5019) (xy 2.5019 2.5019) (xy 2.5019 -2.49682) (xy 3.5179 -2.49682) (xy 3.5179 3.5179)
			)
			(stroke
				(width 0)
				(type default)
			)
			(fill no)
			(layer "F.CrtYd")
		)
		(fp_rect
			(start -3.5179 3.5179)
			(end 3.5179 -3.5179)
			(stroke
				(width 0)
				(type default)
			)
			(fill no)
			(layer "F.Fab")
		)
		(pad "1" smd rect
			(at 1.299972 -2.474722 270)
			(size 0.3556 1.0668)
			(layers "F.Cu" "F.Mask" "F.Paste")
			(net "TPS74801_P1V2_STBY_OUT")
		)
		(pad "2" smd rect
			(at 0.649986 -2.474722 270)
			(size 0.3556 1.0668)
			(layers "F.Cu" "F.Mask" "F.Paste")
			(net "GND")
		)
		(pad "3" smd rect
			(at 0 -2.474722 270)
			(size 0.3556 1.0668)
			(layers "F.Cu" "F.Mask" "F.Paste")
			(net "GND")
		)
		(pad "4" smd rect
			(at -0.649986 -2.474722 270)
			(size 0.3556 1.0668)
			(layers "F.Cu" "F.Mask" "F.Paste")
			(net "GND")
		)
		(pad "5" smd rect
			(at -1.299972 -2.474722 270)
			(size 0.3556 1.0668)
			(layers "F.Cu" "F.Mask" "F.Paste")
			(net "P1V8_STBY")
		)
		(pad "6" smd rect
			(at -2.474722 -1.299972 270)
			(size 1.0668 0.3556)
			(layers "F.Cu" "F.Mask" "F.Paste")
			(net "P1V8_STBY")
		)
		(pad "7" smd rect
			(at -2.474722 -0.649986 270)
			(size 1.0668 0.3556)
			(layers "F.Cu" "F.Mask" "F.Paste")
			(net "P1V8_STBY")
		)
		(pad "8" smd rect
			(at -2.474722 0 270)
			(size 1.0668 0.3556)
			(layers "F.Cu" "F.Mask" "F.Paste")
			(net "P1V8_STBY")
		)
		(pad "9" smd rect
			(at -2.474722 0.649986 270)
			(size 1.0668 0.3556)
			(layers "F.Cu" "F.Mask" "F.Paste")
			(net "PWRGD_P1V2_STBY")
		)
		(pad "10" smd rect
			(at -2.474722 1.299972 270)
			(size 1.0668 0.3556)
			(layers "F.Cu" "F.Mask" "F.Paste")
			(net "TPS74801_P1V2_STBY_BIAS")
		)
		(pad "11" smd rect
			(at -1.299972 2.474722 270)
			(size 0.3556 1.0668)
			(layers "F.Cu" "F.Mask" "F.Paste")
			(net "TPS74801_P1V2_STBY_EN")
		)
		(pad "12" smd rect
			(at -0.649986 2.474722 270)
			(size 0.3556 1.0668)
			(layers "F.Cu" "F.Mask" "F.Paste")
			(net "GND")
		)
		(pad "13" smd rect
			(at 0 2.474722 270)
			(size 0.3556 1.0668)
			(layers "F.Cu" "F.Mask" "F.Paste")
			(net "GND")
		)
		(pad "14" smd rect
			(at 0.649986 2.474722 270)
			(size 0.3556 1.0668)
			(layers "F.Cu" "F.Mask" "F.Paste")
			(net "GND")
		)
		(pad "15" smd rect
			(at 1.299972 2.474722 270)
			(size 0.3556 1.0668)
			(layers "F.Cu" "F.Mask" "F.Paste")
			(net "TPS74801_P1V2_STBY_SS")
		)
		(pad "16" smd rect
			(at 2.474722 1.299972 270)
			(size 1.0668 0.3556)
			(layers "F.Cu" "F.Mask" "F.Paste")
			(net "TPS74801_P1V2_STBY_FB")
		)
		(pad "17" smd rect
			(at 2.474722 0.649986 270)
			(size 1.0668 0.3556)
			(layers "F.Cu" "F.Mask" "F.Paste")
			(net "GND")
		)
		(pad "18" smd rect
			(at 2.474722 0 270)
			(size 1.0668 0.3556)
			(layers "F.Cu" "F.Mask" "F.Paste")
			(net "TPS74801_P1V2_STBY_OUT")
		)
		(pad "19" smd rect
			(at 2.474722 -0.649986 270)
			(size 1.0668 0.3556)
			(layers "F.Cu" "F.Mask" "F.Paste")
			(net "TPS74801_P1V2_STBY_OUT")
		)
		(pad "20" smd rect
			(at 2.474722 -1.299972 270)
			(size 1.0668 0.3556)
			(layers "F.Cu" "F.Mask" "F.Paste")
			(net "TPS74801_P1V2_STBY_OUT")
		)
		(pad "21" smd rect
			(at 0 0 270)
			(size 3.2512 3.2512)
			(layers "F.Cu" "F.Mask" "F.Paste")
			(net "GND")
		)
	)
	(footprint ""
		(layer "F.Cu")
		(at 125.23089 -12.054078 -90)
		(property "Reference" "P1"
			(at 0 0 270)
			(layer "F.SilkS")
			(hide yes)
			(effects
				(font
					(size 1.27 1.27)
				)
			)
		)
		(property "Value" "0R0603-PAD-2-GP-U"
			(at 2.1209 -0.1397 270)
			(unlocked yes)
			(layer "F.Fab")
			(hide yes)
			(effects
				(font
					(size 1.016 1.016)
					(thickness 0.1524)
				)
			)
		)
		(property "Device Type" "0R0603-PAD-1-U"
			(at 2.1209 -1.6637 270)
			(unlocked yes)
			(layer "F.Fab")
			(hide yes)
			(effects
				(font
					(size 1.016 1.016)
					(thickness 0.1524)
				)
			)
		)
		(duplicate_pad_numbers_are_jumpers no)
		(fp_rect
			(start -0.5842 1.3335)
			(end 0.5842 -1.3335)
			(stroke
				(width 0)
				(type default)
			)
			(fill no)
			(layer "F.CrtYd")
		)
		(fp_rect
			(start -0.5842 1.3335)
			(end 0.5842 -1.3335)
			(stroke
				(width 0)
				(type default)
			)
			(fill no)
			(layer "F.Fab")
		)
		(pad "1" smd custom
			(at 0 -0.762 270)
			(size 0.2159 0.2159)
			(layers "F.Cu" "F.Mask" "F.Paste")
			(net "AGND_CURRENT_MON")
			(options
				(clearance outline)
				(anchor circle)
			)
			(primitives
				(gr_poly
					(pts
						(arc
							(start -0.3302 -0.5842)
							(mid -0.402042 -0.554442)
							(end -0.4318 -0.4826)
						)
						(arc
							(start -0.4318 0.4826)
							(mid -0.402042 0.554442)
							(end -0.3302 0.5842)
						)
						(arc
							(start 0.3302 0.5842)
							(mid 0.402042 0.554442)
							(end 0.4318 0.4826)
						)
						(arc
							(start 0.4318 -0.4826)
							(mid 0.402042 -0.554442)
							(end 0.3302 -0.5842)
						)
					)
					(width 0)
					(fill yes)
				)
			)
		)
		(pad "2" smd custom
			(at 0 0.762 270)
			(size 0.2159 0.2159)
			(layers "F.Cu" "F.Mask" "F.Paste")
			(net "GND")
			(options
				(clearance outline)
				(anchor circle)
			)
			(primitives
				(gr_poly
					(pts
						(arc
							(start -0.4318 0.4826)
							(mid -0.402042 0.554442)
							(end -0.3302 0.5842)
						)
						(arc
							(start 0.3302 0.5842)
							(mid 0.402042 0.554442)
							(end 0.4318 0.4826)
						)
						(arc
							(start 0.4318 -0.4826)
							(mid 0.402042 -0.554442)
							(end 0.3302 -0.5842)
						)
						(arc
							(start -0.3302 -0.5842)
							(mid -0.402042 -0.554442)
							(end -0.4318 -0.4826)
						)
					)
					(width 0)
					(fill yes)
				)
			)
		)
	)
	(footprint ""
		(layer "F.Cu")
		(at 23.756874 -125.638814 180)
		(property "Reference" "R346"
			(at 0 0 180)
			(layer "F.SilkS")
			(hide yes)
			(effects
				(font
					(size 1.27 1.27)
				)
			)
		)
		(property "Value" "150R2F-1-GP"
			(at 0.064008 -3.993896 180)
			(unlocked yes)
			(layer "F.Fab")
			(hide yes)
			(effects
				(font
					(size 1.016 1.016)
					(thickness 0.1524)
				)
			)
		)
		(property "Device Type" "R402H16"
			(at 0.064008 -5.517896 180)
			(unlocked yes)
			(layer "F.Fab")
			(hide yes)
			(effects
				(font
					(size 1.016 1.016)
					(thickness 0.1524)
				)
			)
		)
		(duplicate_pad_numbers_are_jumpers no)
		(fp_line
			(start 0.508 -0.9398)
			(end -0.508 -0.9398)
			(stroke
				(width 0.1524)
				(type default)
			)
			(layer "F.SilkS")
		)
		(fp_line
			(start -0.508 -0.9398)
			(end -0.508 0.9398)
			(stroke
				(width 0.1524)
				(type default)
			)
			(layer "F.SilkS")
		)
		(fp_rect
			(start -0.508 0.9398)
			(end 0.508 -0.9398)
			(stroke
				(width 0)
				(type default)
			)
			(fill no)
			(layer "F.CrtYd")
		)
		(fp_rect
			(start -0.508 0.9398)
			(end 0.508 -0.9398)
			(stroke
				(width 0)
				(type default)
			)
			(fill no)
			(layer "F.Fab")
		)
		(pad "1" smd custom
			(at 0 -0.4445 180)
			(size 0.1397 0.1397)
			(layers "F.Cu" "F.Mask" "F.Paste")
			(net "P3V3_STBY")
			(options
				(clearance outline)
				(anchor circle)
			)
			(primitives
				(gr_poly
					(pts
						(arc
							(start -0.1778 -0.2794)
							(mid -0.249642 -0.249642)
							(end -0.2794 -0.1778)
						)
						(arc
							(start -0.2794 0.1778)
							(mid -0.249642 0.249642)
							(end -0.1778 0.2794)
						)
						(arc
							(start 0.1778 0.2794)
							(mid 0.249642 0.249642)
							(end 0.2794 0.1778)
						)
						(arc
							(start 0.2794 -0.1778)
							(mid 0.249642 -0.249642)
							(end 0.1778 -0.2794)
						)
					)
					(width 0)
					(fill yes)
				)
			)
		)
		(pad "2" smd custom
			(at 0 0.4445 180)
			(size 0.1397 0.1397)
			(layers "F.Cu" "F.Mask" "F.Paste")
			(net "BMC_HBLED_R")
			(options
				(clearance outline)
				(anchor circle)
			)
			(primitives
				(gr_poly
					(pts
						(arc
							(start -0.1778 -0.2794)
							(mid -0.249642 -0.249642)
							(end -0.2794 -0.1778)
						)
						(arc
							(start -0.2794 0.1778)
							(mid -0.249642 0.249642)
							(end -0.1778 0.2794)
						)
						(arc
							(start 0.1778 0.2794)
							(mid 0.249642 0.249642)
							(end 0.2794 0.1778)
						)
						(arc
							(start 0.2794 -0.1778)
							(mid 0.249642 -0.249642)
							(end 0.1778 -0.2794)
						)
					)
					(width 0)
					(fill yes)
				)
			)
		)
	)
	(footprint ""
		(layer "F.Cu")
		(at 134.441438 -12.737592 -90)
		(property "Reference" "R443"
			(at 0 0 270)
			(layer "F.SilkS")
			(hide yes)
			(effects
				(font
					(size 1.27 1.27)
				)
			)
		)
		(property "Value" "10R2F-L-GP"
			(at 0.064008 -3.993896 270)
			(unlocked yes)
			(layer "F.Fab")
			(hide yes)
			(effects
				(font
					(size 1.016 1.016)
					(thickness 0.1524)
				)
			)
		)
		(property "Device Type" "R402H14"
			(at 0.064008 -5.517896 270)
			(unlocked yes)
			(layer "F.Fab")
			(hide yes)
			(effects
				(font
					(size 1.016 1.016)
					(thickness 0.1524)
				)
			)
		)
		(duplicate_pad_numbers_are_jumpers no)
		(fp_line
			(start -0.508 -0.9398)
			(end -0.508 0.9398)
			(stroke
				(width 0.1524)
				(type default)
			)
			(layer "F.SilkS")
		)
		(fp_line
			(start 0.508 -0.9398)
			(end -0.508 -0.9398)
			(stroke
				(width 0.1524)
				(type default)
			)
			(layer "F.SilkS")
		)
		(fp_rect
			(start -0.508 0.9398)
			(end 0.508 -0.9398)
			(stroke
				(width 0)
				(type default)
			)
			(fill no)
			(layer "F.CrtYd")
		)
		(fp_rect
			(start -0.508 0.9398)
			(end 0.508 -0.9398)
			(stroke
				(width 0)
				(type default)
			)
			(fill no)
			(layer "F.Fab")
		)
		(pad "1" smd custom
			(at 0 -0.4445 270)
			(size 0.1397 0.1397)
			(layers "F.Cu" "F.Mask" "F.Paste")
			(net "MB0_CM_SENSE_R1_N")
			(options
				(clearance outline)
				(anchor circle)
			)
			(primitives
				(gr_poly
					(pts
						(arc
							(start -0.1778 -0.2794)
							(mid -0.249642 -0.249642)
							(end -0.2794 -0.1778)
						)
						(arc
							(start -0.2794 0.1778)
							(mid -0.249642 0.249642)
							(end -0.1778 0.2794)
						)
						(arc
							(start 0.1778 0.2794)
							(mid 0.249642 0.249642)
							(end 0.2794 0.1778)
						)
						(arc
							(start 0.2794 -0.1778)
							(mid 0.249642 -0.249642)
							(end 0.1778 -0.2794)
						)
					)
					(width 0)
					(fill yes)
				)
			)
		)
		(pad "2" smd custom
			(at 0 0.4445 270)
			(size 0.1397 0.1397)
			(layers "F.Cu" "F.Mask" "F.Paste")
			(net "ADM1278_HS_N")
			(options
				(clearance outline)
				(anchor circle)
			)
			(primitives
				(gr_poly
					(pts
						(arc
							(start -0.1778 -0.2794)
							(mid -0.249642 -0.249642)
							(end -0.2794 -0.1778)
						)
						(arc
							(start -0.2794 0.1778)
							(mid -0.249642 0.249642)
							(end -0.1778 0.2794)
						)
						(arc
							(start 0.1778 0.2794)
							(mid 0.249642 0.249642)
							(end 0.2794 0.1778)
						)
						(arc
							(start 0.2794 -0.1778)
							(mid 0.249642 -0.249642)
							(end 0.1778 -0.2794)
						)
					)
					(width 0)
					(fill yes)
				)
			)
		)
	)
)
